# T6G (Grand Teton) — schematic netlist excerpt (pin names and nets, part order shuffled) for the footprints in the layout excerpt that follows; sources: Cadence DE-HDL packaged netlist, KiCad conversion of 04192023_DAF0TMB3IC0_F0TG_MB_C_brd_V02_OCP.brd

C86  Q_CAP  0.01UF 50V 10% EMPTY  pkg C0402  page 172 : A = JTAG_TDI ; B = GND

PPQ6  MOSFET_NCH_1D3S  PSMNR58-30YLH IC  pkg SOT1023  page 266
  \1\  = P12V_AUX
  \2\  = P12V_AUX
  \3\  = P12V_AUX
  \4\  = P12V_HSC_GATE_G2
  \5\  = P12V_MAIN_R

(kicad_pcb
	(version 20260206)
	(generator "pcbnew")
	(generator_version "10.0")
	(general
		(thickness 1.6)
		(legacy_teardrops no)
	)
	(paper "A4")
	(title_block
		(title "04192023_DAF0TMB3IC0_F0TG_MB_C_brd_V02_OCP.brd")
		(comment 1 "Grand Teton / footprints 191-192 of 8354")
	)
	(layers
		(0 "F.Cu" signal "TOP")
		(4 "In1.Cu" signal "GND")
		(6 "In2.Cu" signal "IN1")
		(8 "In3.Cu" signal "GND1")
		(10 "In4.Cu" signal "IN2")
		(12 "In5.Cu" signal "GND2")
		(14 "In6.Cu" signal "IN3")
		(16 "In7.Cu" signal "GND3")
		(18 "In8.Cu" signal "VCC")
		(20 "In9.Cu" signal "VCC1")
		(22 "In10.Cu" signal "GND4")
		(24 "In11.Cu" signal "IN4")
		(26 "In12.Cu" signal "GND5")
		(28 "In13.Cu" signal "IN5")
		(30 "In14.Cu" signal "GND6")
		(32 "In15.Cu" signal "IN6")
		(34 "In16.Cu" signal "GND7")
		(2 "B.Cu" signal "BOTTOM")
		(9 "F.Adhes" user "F.Adhesive")
		(11 "B.Adhes" user "B.Adhesive")
		(13 "F.Paste" user "Package Geometry/Pastemask Top")
		(15 "B.Paste" user "Package Geometry/Pastemask Bottom")
		(5 "F.SilkS" user "Ref Des/Silkscreen Top")
		(7 "B.SilkS" user "Ref Des/Silkscreen Bottom")
		(1 "F.Mask" user "Board Geometry/Soldermask Top")
		(3 "B.Mask" user "Board Geometry/Soldermask Bottom")
		(17 "Dwgs.User" user "User.Drawings")
		(19 "Cmts.User" user "User.Comments")
		(21 "Eco1.User" user "User.Eco1")
		(23 "Eco2.User" user "User.Eco2")
		(25 "Edge.Cuts" user "Board Geometry/Outline")
		(27 "Margin" user)
		(31 "F.CrtYd" user "Package Geometry/Place Bound Top")
		(29 "B.CrtYd" user "Package Geometry/Place Bound Bottom")
		(35 "F.Fab" user "Ref Des/Assembly Top")
		(33 "B.Fab" user "Ref Des/Assembly Bottom")
	)
	(footprint ""
		(layer "F.Cu")
		(at 127.705104 -53.15839 180)
		(property "Reference" "C86"
			(at 0 0 180)
			(layer "F.SilkS")
			(hide yes)
			(effects
				(font
					(size 1.27 1.27)
				)
			)
		)
		(property "Value" ""
			(at 0 0 180)
			(layer "F.Fab")
			(effects
				(font
					(size 1.27 1.27)
				)
			)
		)
		(duplicate_pad_numbers_are_jumpers no)
		(fp_line
			(start 0.7874 0.4064)
			(end -0.7874 0.4064)
			(stroke
				(width 0.1524)
				(type default)
			)
			(layer "F.SilkS")
		)
		(fp_line
			(start 0.7874 -0.4064)
			(end 0.7874 0.4064)
			(stroke
				(width 0.1524)
				(type default)
			)
			(layer "F.SilkS")
		)
		(fp_line
			(start -0.7874 0.4064)
			(end -0.7874 -0.4064)
			(stroke
				(width 0.1524)
				(type default)
			)
			(layer "F.SilkS")
		)
		(fp_line
			(start -0.7874 -0.4064)
			(end 0.7874 -0.4064)
			(stroke
				(width 0.1524)
				(type default)
			)
			(layer "F.SilkS")
		)
		(fp_line
			(start 0.67945 0.3048)
			(end 0.120396 0.3048)
			(stroke
				(width 0.1)
				(type default)
			)
			(layer "F.Fab")
		)
		(fp_line
			(start 0.67945 -0.3048)
			(end 0.67945 0.3048)
			(stroke
				(width 0.1)
				(type default)
			)
			(layer "F.Fab")
		)
		(fp_line
			(start 0.12065 -0.2794)
			(end 0.12065 -0.3048)
			(stroke
				(width 0.1)
				(type default)
			)
			(layer "F.Fab")
		)
		(fp_line
			(start 0.12065 -0.3048)
			(end 0.67945 -0.3048)
			(stroke
				(width 0.1)
				(type default)
			)
			(layer "F.Fab")
		)
		(fp_line
			(start 0.120396 0.3048)
			(end 0.120396 0.2794)
			(stroke
				(width 0.1)
				(type default)
			)
			(layer "F.Fab")
		)
		(fp_line
			(start 0.120396 0.2794)
			(end -0.12065 0.2794)
			(stroke
				(width 0.1)
				(type default)
			)
			(layer "F.Fab")
		)
		(fp_line
			(start -0.12065 0.3048)
			(end -0.67945 0.3048)
			(stroke
				(width 0.1)
				(type default)
			)
			(layer "F.Fab")
		)
		(fp_line
			(start -0.12065 0.2794)
			(end -0.12065 0.3048)
			(stroke
				(width 0.1)
				(type default)
			)
			(layer "F.Fab")
		)
		(fp_line
			(start -0.12065 -0.2794)
			(end 0.12065 -0.2794)
			(stroke
				(width 0.1)
				(type default)
			)
			(layer "F.Fab")
		)
		(fp_line
			(start -0.12065 -0.305054)
			(end -0.12065 -0.2794)
			(stroke
				(width 0.1)
				(type default)
			)
			(layer "F.Fab")
		)
		(fp_line
			(start -0.67945 0.3048)
			(end -0.67945 -0.305054)
			(stroke
				(width 0.1)
				(type default)
			)
			(layer "F.Fab")
		)
		(fp_line
			(start -0.67945 -0.305054)
			(end -0.12065 -0.305054)
			(stroke
				(width 0.1)
				(type default)
			)
			(layer "F.Fab")
		)
		(pad "1" smd circle
			(at -0.40005 0 180)
			(size 0 0)
			(layers "F.Cu" "F.Mask" "F.Paste")
			(net "JTAG_TDI")
		)
		(pad "2" smd circle
			(at 0.40005 0 180)
			(size 0 0)
			(layers "F.Cu" "F.Mask" "F.Paste")
			(net "GND")
		)
	)
	(footprint ""
		(layer "F.Cu")
		(at 259.461 -385.27736 90)
		(property "Reference" "PPQ6"
			(at -7.487412 -2.39268 0)
			(unlocked yes)
			(layer "F.SilkS")
			(effects
				(font
					(size 0.7874 0.5842)
					(thickness 0.1524)
				)
				(justify left)
			)
		)
		(property "Value" ""
			(at 0 0 90)
			(layer "F.Fab")
			(effects
				(font
					(size 1.27 1.27)
				)
			)
		)
		(duplicate_pad_numbers_are_jumpers no)
		(fp_line
			(start 2.350008 -2.649982)
			(end 2.350008 -2.4892)
			(stroke
				(width 0.1524)
				(type default)
			)
			(layer "F.SilkS")
		)
		(fp_line
			(start -2.350008 -2.649982)
			(end 2.350008 -2.649982)
			(stroke
				(width 0.1524)
				(type default)
			)
			(layer "F.SilkS")
		)
		(fp_line
			(start -2.350008 -2.4384)
			(end -2.350008 -2.649982)
			(stroke
				(width 0.1524)
				(type default)
			)
			(layer "F.SilkS")
		)
		(fp_line
			(start 2.350008 2.4892)
			(end 2.350008 2.649982)
			(stroke
				(width 0.1524)
				(type default)
			)
			(layer "F.SilkS")
		)
		(fp_line
			(start 2.350008 2.649982)
			(end -2.350008 2.649982)
			(stroke
				(width 0.1524)
				(type default)
			)
			(layer "F.SilkS")
		)
		(fp_line
			(start -2.350008 2.649982)
			(end -2.350008 2.413)
			(stroke
				(width 0.1524)
				(type default)
			)
			(layer "F.SilkS")
		)
		(fp_poly
			(pts
				(xy -3.506216 -3.488944) (xy -2.706116 -3.488944) (xy -3.125216 -2.447544)
			)
			(stroke
				(width 0)
				(type default)
			)
			(fill yes)
			(layer "F.SilkS")
		)
		(fp_line
			(start 2.350008 -2.649982)
			(end 2.350008 2.649982)
			(stroke
				(width 0.1)
				(type default)
			)
			(layer "F.Fab")
		)
		(fp_line
			(start -2.350008 -2.649982)
			(end 2.350008 -2.649982)
			(stroke
				(width 0.1)
				(type default)
			)
			(layer "F.Fab")
		)
		(fp_line
			(start 2.350008 2.649982)
			(end -2.350008 2.649982)
			(stroke
				(width 0.1)
				(type default)
			)
			(layer "F.Fab")
		)
		(fp_line
			(start -2.350008 2.649982)
			(end -2.350008 -2.649982)
			(stroke
				(width 0.1)
				(type default)
			)
			(layer "F.Fab")
		)
		(fp_poly
			(pts
				(xy -3.717544 -1.905) (xy -4.758944 -2.3241) (xy -4.758944 -1.524)
			)
			(stroke
				(width 0)
				(type default)
			)
			(fill yes)
			(layer "F.Fab")
		)
		(pad "1" smd rect
			(at -2.999994 -1.905)
			(size 0.7112 1.1684)
			(layers "F.Cu" "F.Mask" "F.Paste")
			(net "P12V_AUX")
		)
		(pad "2" smd rect
			(at -2.999994 -0.635)
			(size 0.7112 1.1684)
			(layers "F.Cu" "F.Mask" "F.Paste")
			(net "P12V_AUX")
		)
		(pad "3" smd rect
			(at -2.999994 0.635)
			(size 0.7112 1.1684)
			(layers "F.Cu" "F.Mask" "F.Paste")
			(net "P12V_AUX")
		)
		(pad "4" smd rect
			(at -2.999994 1.905)
			(size 0.7112 1.1684)
			(layers "F.Cu" "F.Mask" "F.Paste")
			(net "P12V_HSC_GATE_G2")
		)
		(pad "5" smd circle
			(at 0.925068 0)
			(size 0 0)
			(layers "F.Cu" "F.Mask" "F.Paste")
			(net "P12V_MAIN_R")
		)
		(zone
			(layer "F.Cu")
			(hatch none 0.5)
			(connect_pads
				(clearance 0)
			)
			(min_thickness 0.25)
			(keepout
				(tracks not_allowed)
				(vias allowed)
				(pads allowed)
				(copperpour not_allowed)
				(footprints allowed)
			)
			(placement
				(enabled no)
				(sheetname "")
			)
			(fill
				(thermal_gap 0.5)
				(thermal_bridge_width 0.5)
				(island_removal_mode 0)
			)
			(polygon
				(pts
					(xy 256.8194 -383.7178) (xy 262.1026 -383.7178) (xy 262.1026 -382.92786) (xy 256.8194 -382.92786)
				)
			)
		)
	)
)
